(kicad_pcb
	(version 20260206)
	(generator "pcbnew")
	(generator_version "10.0")
	(general
		(thickness 1.6)
		(legacy_teardrops no)
	)
	(paper "A4")
	(title_block
		(title "03242023_DA0F0TMBIJ0_F0T_Motherboard_J_brd_V01_OCP.brd")
		(comment 1 "Grand Teton / footprints 4649-4654 of 6105")
	)
	(layers
		(0 "F.Cu" signal "TOP")
		(4 "In1.Cu" signal "GND")
		(6 "In2.Cu" signal "IN1")
		(8 "In3.Cu" signal "GND1")
		(10 "In4.Cu" signal "IN2")
		(12 "In5.Cu" signal "GND2")
		(14 "In6.Cu" signal "IN3")
		(16 "In7.Cu" signal "GND3")
		(18 "In8.Cu" signal "VCC")
		(20 "In9.Cu" signal "VCC1")
		(22 "In10.Cu" signal "GND4")
		(24 "In11.Cu" signal "IN4")
		(26 "In12.Cu" signal "GND5")
		(28 "In13.Cu" signal "IN5")
		(30 "In14.Cu" signal "GND6")
		(32 "In15.Cu" signal "IN6")
		(34 "In16.Cu" signal "GND7")
		(2 "B.Cu" signal "BOTTOM")
		(9 "F.Adhes" user "F.Adhesive")
		(11 "B.Adhes" user "B.Adhesive")
		(13 "F.Paste" user "Package Geometry/Pastemask Top")
		(15 "B.Paste" user "Package Geometry/Pastemask Bottom")
		(5 "F.SilkS" user "Ref Des/Silkscreen Top")
		(7 "B.SilkS" user "Ref Des/Silkscreen Bottom")
		(1 "F.Mask" user "Board Geometry/Soldermask Top")
		(3 "B.Mask" user "Board Geometry/Soldermask Bottom")
		(17 "Dwgs.User" user "User.Drawings")
		(19 "Cmts.User" user "User.Comments")
		(21 "Eco1.User" user "User.Eco1")
		(23 "Eco2.User" user "User.Eco2")
		(25 "Edge.Cuts" user "Board Geometry/Outline")
		(27 "Margin" user)
		(31 "F.CrtYd" user "Package Geometry/Place Bound Top")
		(29 "B.CrtYd" user "Package Geometry/Place Bound Bottom")
		(35 "F.Fab" user "Ref Des/Assembly Top")
		(33 "B.Fab" user "Ref Des/Assembly Bottom")
	)
	(footprint ""
		(layer "B.Cu")
		(at 110.874556 -416.030918 90)
		(property "Reference" "C2329"
			(at 0 0 90)
			(layer "B.SilkS")
			(hide yes)
			(effects
				(font
					(size 1.27 1.27)
				)
				(justify mirror)
			)
		)
		(property "Value" ""
			(at 0 0 90)
			(layer "B.Fab")
			(effects
				(font
					(size 1.27 1.27)
				)
				(justify mirror)
			)
		)
		(duplicate_pad_numbers_are_jumpers no)
		(fp_line
			(start 0.7874 -0.4064)
			(end -0.7874 -0.4064)
			(stroke
				(width 0.1524)
				(type default)
			)
			(layer "B.SilkS")
		)
		(fp_line
			(start -0.7874 -0.4064)
			(end -0.7874 0.4064)
			(stroke
				(width 0.1524)
				(type default)
			)
			(layer "B.SilkS")
		)
		(fp_line
			(start 0.7874 0.4064)
			(end 0.7874 -0.4064)
			(stroke
				(width 0.1524)
				(type default)
			)
			(layer "B.SilkS")
		)
		(fp_line
			(start -0.7874 0.4064)
			(end 0.7874 0.4064)
			(stroke
				(width 0.1524)
				(type default)
			)
			(layer "B.SilkS")
		)
		(fp_line
			(start 0.67945 -0.305054)
			(end 0.12065 -0.305054)
			(stroke
				(width 0.1)
				(type default)
			)
			(layer "B.Fab")
		)
		(fp_line
			(start 0.12065 -0.305054)
			(end 0.12065 -0.2794)
			(stroke
				(width 0.1)
				(type default)
			)
			(layer "B.Fab")
		)
		(fp_line
			(start -0.12065 -0.3048)
			(end -0.67945 -0.3048)
			(stroke
				(width 0.1)
				(type default)
			)
			(layer "B.Fab")
		)
		(fp_line
			(start -0.67945 -0.3048)
			(end -0.67945 0.3048)
			(stroke
				(width 0.1)
				(type default)
			)
			(layer "B.Fab")
		)
		(fp_line
			(start 0.12065 -0.2794)
			(end -0.12065 -0.2794)
			(stroke
				(width 0.1)
				(type default)
			)
			(layer "B.Fab")
		)
		(fp_line
			(start -0.12065 -0.2794)
			(end -0.12065 -0.3048)
			(stroke
				(width 0.1)
				(type default)
			)
			(layer "B.Fab")
		)
		(fp_line
			(start 0.12065 0.2794)
			(end 0.12065 0.3048)
			(stroke
				(width 0.1)
				(type default)
			)
			(layer "B.Fab")
		)
		(fp_line
			(start -0.120396 0.2794)
			(end 0.12065 0.2794)
			(stroke
				(width 0.1)
				(type default)
			)
			(layer "B.Fab")
		)
		(fp_line
			(start 0.67945 0.3048)
			(end 0.67945 -0.305054)
			(stroke
				(width 0.1)
				(type default)
			)
			(layer "B.Fab")
		)
		(fp_line
			(start 0.12065 0.3048)
			(end 0.67945 0.3048)
			(stroke
				(width 0.1)
				(type default)
			)
			(layer "B.Fab")
		)
		(fp_line
			(start -0.120396 0.3048)
			(end -0.120396 0.2794)
			(stroke
				(width 0.1)
				(type default)
			)
			(layer "B.Fab")
		)
		(fp_line
			(start -0.67945 0.3048)
			(end -0.120396 0.3048)
			(stroke
				(width 0.1)
				(type default)
			)
			(layer "B.Fab")
		)
		(pad "1" smd circle
			(at 0.40005 0 270)
			(size 0 0)
			(layers "B.Cu" "B.Mask" "B.Paste")
			(net "P3V3_9ZXL045_VDD")
		)
		(pad "2" smd circle
			(at -0.40005 0 270)
			(size 0 0)
			(layers "B.Cu" "B.Mask" "B.Paste")
			(net "GND")
		)
	)
	(footprint ""
		(layer "B.Cu")
		(at 94.596712 -334.752442 -90)
		(property "Reference" "PR328"
			(at 0 0 90)
			(layer "B.SilkS")
			(hide yes)
			(effects
				(font
					(size 1.27 1.27)
				)
				(justify mirror)
			)
		)
		(property "Value" ""
			(at 0 0 90)
			(layer "B.Fab")
			(effects
				(font
					(size 1.27 1.27)
				)
				(justify mirror)
			)
		)
		(duplicate_pad_numbers_are_jumpers no)
		(fp_line
			(start -0.7874 0.4064)
			(end 0.7874 0.4064)
			(stroke
				(width 0.1524)
				(type default)
			)
			(layer "B.SilkS")
		)
		(fp_line
			(start 0.7874 0.4064)
			(end 0.7874 -0.4064)
			(stroke
				(width 0.1524)
				(type default)
			)
			(layer "B.SilkS")
		)
		(fp_line
			(start -0.7874 -0.4064)
			(end -0.7874 0.4064)
			(stroke
				(width 0.1524)
				(type default)
			)
			(layer "B.SilkS")
		)
		(fp_line
			(start 0.7874 -0.4064)
			(end -0.7874 -0.4064)
			(stroke
				(width 0.1524)
				(type default)
			)
			(layer "B.SilkS")
		)
		(fp_line
			(start -0.67945 0.3048)
			(end -0.120396 0.3048)
			(stroke
				(width 0.1)
				(type default)
			)
			(layer "B.Fab")
		)
		(fp_line
			(start -0.120396 0.3048)
			(end -0.120396 0.2794)
			(stroke
				(width 0.1)
				(type default)
			)
			(layer "B.Fab")
		)
		(fp_line
			(start 0.12065 0.3048)
			(end 0.67945 0.3048)
			(stroke
				(width 0.1)
				(type default)
			)
			(layer "B.Fab")
		)
		(fp_line
			(start 0.67945 0.3048)
			(end 0.67945 -0.305054)
			(stroke
				(width 0.1)
				(type default)
			)
			(layer "B.Fab")
		)
		(fp_line
			(start -0.120396 0.2794)
			(end 0.12065 0.2794)
			(stroke
				(width 0.1)
				(type default)
			)
			(layer "B.Fab")
		)
		(fp_line
			(start 0.12065 0.2794)
			(end 0.12065 0.3048)
			(stroke
				(width 0.1)
				(type default)
			)
			(layer "B.Fab")
		)
		(fp_line
			(start -0.12065 -0.2794)
			(end -0.12065 -0.3048)
			(stroke
				(width 0.1)
				(type default)
			)
			(layer "B.Fab")
		)
		(fp_line
			(start 0.12065 -0.2794)
			(end -0.12065 -0.2794)
			(stroke
				(width 0.1)
				(type default)
			)
			(layer "B.Fab")
		)
		(fp_line
			(start -0.67945 -0.3048)
			(end -0.67945 0.3048)
			(stroke
				(width 0.1)
				(type default)
			)
			(layer "B.Fab")
		)
		(fp_line
			(start -0.12065 -0.3048)
			(end -0.67945 -0.3048)
			(stroke
				(width 0.1)
				(type default)
			)
			(layer "B.Fab")
		)
		(fp_line
			(start 0.12065 -0.305054)
			(end 0.12065 -0.2794)
			(stroke
				(width 0.1)
				(type default)
			)
			(layer "B.Fab")
		)
		(fp_line
			(start 0.67945 -0.305054)
			(end 0.12065 -0.305054)
			(stroke
				(width 0.1)
				(type default)
			)
			(layer "B.Fab")
		)
		(pad "1" smd circle
			(at 0.40005 0 90)
			(size 0 0)
			(layers "B.Cu" "B.Mask" "B.Paste")
			(net "PVCCIN_CPU1_PVCC")
		)
		(pad "2" smd circle
			(at -0.40005 0 90)
			(size 0 0)
			(layers "B.Cu" "B.Mask" "B.Paste")
			(net "PVCCIN_CPU1_VDD1")
		)
	)
	(footprint ""
		(layer "B.Cu")
		(at 291.588698 -152.176988)
		(property "Reference" "R691"
			(at 0 0 0)
			(layer "B.SilkS")
			(hide yes)
			(effects
				(font
					(size 1.27 1.27)
				)
				(justify mirror)
			)
		)
		(property "Value" ""
			(at 0 0 0)
			(layer "B.Fab")
			(effects
				(font
					(size 1.27 1.27)
				)
				(justify mirror)
			)
		)
		(duplicate_pad_numbers_are_jumpers no)
		(fp_line
			(start -0.7874 -0.4064)
			(end -0.7874 0.4064)
			(stroke
				(width 0.1524)
				(type default)
			)
			(layer "B.SilkS")
		)
		(fp_line
			(start -0.7874 0.4064)
			(end 0.7874 0.4064)
			(stroke
				(width 0.1524)
				(type default)
			)
			(layer "B.SilkS")
		)
		(fp_line
			(start 0.7874 -0.4064)
			(end -0.7874 -0.4064)
			(stroke
				(width 0.1524)
				(type default)
			)
			(layer "B.SilkS")
		)
		(fp_line
			(start 0.7874 0.4064)
			(end 0.7874 -0.4064)
			(stroke
				(width 0.1524)
				(type default)
			)
			(layer "B.SilkS")
		)
		(fp_line
			(start -0.67945 -0.3048)
			(end -0.67945 0.3048)
			(stroke
				(width 0.1)
				(type default)
			)
			(layer "B.Fab")
		)
		(fp_line
			(start -0.67945 0.3048)
			(end -0.120396 0.3048)
			(stroke
				(width 0.1)
				(type default)
			)
			(layer "B.Fab")
		)
		(fp_line
			(start -0.12065 -0.3048)
			(end -0.67945 -0.3048)
			(stroke
				(width 0.1)
				(type default)
			)
			(layer "B.Fab")
		)
		(fp_line
			(start -0.12065 -0.2794)
			(end -0.12065 -0.3048)
			(stroke
				(width 0.1)
				(type default)
			)
			(layer "B.Fab")
		)
		(fp_line
			(start -0.120396 0.2794)
			(end 0.12065 0.2794)
			(stroke
				(width 0.1)
				(type default)
			)
			(layer "B.Fab")
		)
		(fp_line
			(start -0.120396 0.3048)
			(end -0.120396 0.2794)
			(stroke
				(width 0.1)
				(type default)
			)
			(layer "B.Fab")
		)
		(fp_line
			(start 0.12065 -0.305054)
			(end 0.12065 -0.2794)
			(stroke
				(width 0.1)
				(type default)
			)
			(layer "B.Fab")
		)
		(fp_line
			(start 0.12065 -0.2794)
			(end -0.12065 -0.2794)
			(stroke
				(width 0.1)
				(type default)
			)
			(layer "B.Fab")
		)
		(fp_line
			(start 0.12065 0.2794)
			(end 0.12065 0.3048)
			(stroke
				(width 0.1)
				(type default)
			)
			(layer "B.Fab")
		)
		(fp_line
			(start 0.12065 0.3048)
			(end 0.67945 0.3048)
			(stroke
				(width 0.1)
				(type default)
			)
			(layer "B.Fab")
		)
		(fp_line
			(start 0.67945 -0.305054)
			(end 0.12065 -0.305054)
			(stroke
				(width 0.1)
				(type default)
			)
			(layer "B.Fab")
		)
		(fp_line
			(start 0.67945 0.3048)
			(end 0.67945 -0.305054)
			(stroke
				(width 0.1)
				(type default)
			)
			(layer "B.Fab")
		)
		(pad "1" smd circle
			(at 0.40005 0 180)
			(size 0 0)
			(layers "B.Cu" "B.Mask" "B.Paste")
			(net "I3C_SPD_DDRABCD_CPU0_LVC1_R_SCL")
		)
		(pad "2" smd circle
			(at -0.40005 0 180)
			(size 0 0)
			(layers "B.Cu" "B.Mask" "B.Paste")
			(net "I3C_SPD_DDRABCD_CPU0_LVC1_SCL")
		)
	)
	(footprint ""
		(layer "B.Cu")
		(at 315.284358 -230.50119)
		(property "Reference" "R1241"
			(at 0 0 0)
			(layer "B.SilkS")
			(hide yes)
			(effects
				(font
					(size 1.27 1.27)
				)
				(justify mirror)
			)
		)
		(property "Value" ""
			(at 0 0 0)
			(layer "B.Fab")
			(effects
				(font
					(size 1.27 1.27)
				)
				(justify mirror)
			)
		)
		(duplicate_pad_numbers_are_jumpers no)
		(fp_line
			(start -0.7874 -0.4064)
			(end -0.7874 0.4064)
			(stroke
				(width 0.1524)
				(type default)
			)
			(layer "B.SilkS")
		)
		(fp_line
			(start -0.7874 0.4064)
			(end 0.7874 0.4064)
			(stroke
				(width 0.1524)
				(type default)
			)
			(layer "B.SilkS")
		)
		(fp_line
			(start 0.7874 -0.4064)
			(end -0.7874 -0.4064)
			(stroke
				(width 0.1524)
				(type default)
			)
			(layer "B.SilkS")
		)
		(fp_line
			(start 0.7874 0.4064)
			(end 0.7874 -0.4064)
			(stroke
				(width 0.1524)
				(type default)
			)
			(layer "B.SilkS")
		)
		(fp_line
			(start -0.67945 -0.3048)
			(end -0.67945 0.3048)
			(stroke
				(width 0.1)
				(type default)
			)
			(layer "B.Fab")
		)
		(fp_line
			(start -0.67945 0.3048)
			(end -0.120396 0.3048)
			(stroke
				(width 0.1)
				(type default)
			)
			(layer "B.Fab")
		)
		(fp_line
			(start -0.12065 -0.3048)
			(end -0.67945 -0.3048)
			(stroke
				(width 0.1)
				(type default)
			)
			(layer "B.Fab")
		)
		(fp_line
			(start -0.12065 -0.2794)
			(end -0.12065 -0.3048)
			(stroke
				(width 0.1)
				(type default)
			)
			(layer "B.Fab")
		)
		(fp_line
			(start -0.120396 0.2794)
			(end 0.12065 0.2794)
			(stroke
				(width 0.1)
				(type default)
			)
			(layer "B.Fab")
		)
		(fp_line
			(start -0.120396 0.3048)
			(end -0.120396 0.2794)
			(stroke
				(width 0.1)
				(type default)
			)
			(layer "B.Fab")
		)
		(fp_line
			(start 0.12065 -0.305054)
			(end 0.12065 -0.2794)
			(stroke
				(width 0.1)
				(type default)
			)
			(layer "B.Fab")
		)
		(fp_line
			(start 0.12065 -0.2794)
			(end -0.12065 -0.2794)
			(stroke
				(width 0.1)
				(type default)
			)
			(layer "B.Fab")
		)
		(fp_line
			(start 0.12065 0.2794)
			(end 0.12065 0.3048)
			(stroke
				(width 0.1)
				(type default)
			)
			(layer "B.Fab")
		)
		(fp_line
			(start 0.12065 0.3048)
			(end 0.67945 0.3048)
			(stroke
				(width 0.1)
				(type default)
			)
			(layer "B.Fab")
		)
		(fp_line
			(start 0.67945 -0.305054)
			(end 0.12065 -0.305054)
			(stroke
				(width 0.1)
				(type default)
			)
			(layer "B.Fab")
		)
		(fp_line
			(start 0.67945 0.3048)
			(end 0.67945 -0.305054)
			(stroke
				(width 0.1)
				(type default)
			)
			(layer "B.Fab")
		)
		(pad "1" smd circle
			(at 0.40005 0 180)
			(size 0 0)
			(layers "B.Cu" "B.Mask" "B.Paste")
			(net "H_PMAX_TRIGGER_IO_CPU0")
		)
		(pad "2" smd circle
			(at -0.40005 0 180)
			(size 0 0)
			(layers "B.Cu" "B.Mask" "B.Paste")
			(net "GND")
		)
	)
	(footprint ""
		(layer "B.Cu")
		(at 62.996572 -159.87268)
		(property "Reference" "PC457_P1_1"
			(at 0 0 0)
			(layer "B.SilkS")
			(hide yes)
			(effects
				(font
					(size 1.27 1.27)
				)
				(justify mirror)
			)
		)
		(property "Value" ""
			(at 0 0 0)
			(layer "B.Fab")
			(effects
				(font
					(size 1.27 1.27)
				)
				(justify mirror)
			)
		)
		(duplicate_pad_numbers_are_jumpers no)
		(fp_line
			(start -1.524 -0.762)
			(end -1.524 0.762)
			(stroke
				(width 0.1524)
				(type default)
			)
			(layer "B.SilkS")
		)
		(fp_line
			(start -1.524 0.762)
			(end 1.524 0.762)
			(stroke
				(width 0.1524)
				(type default)
			)
			(layer "B.SilkS")
		)
		(fp_line
			(start 1.524 -0.762)
			(end -1.524 -0.762)
			(stroke
				(width 0.1524)
				(type default)
			)
			(layer "B.SilkS")
		)
		(fp_line
			(start 1.524 0.762)
			(end 1.524 -0.762)
			(stroke
				(width 0.1524)
				(type default)
			)
			(layer "B.SilkS")
		)
		(fp_line
			(start -1.1049 -0.724916)
			(end 1.1049 -0.724916)
			(stroke
				(width 0.1)
				(type default)
			)
			(layer "B.Fab")
		)
		(fp_line
			(start -1.1049 0.724916)
			(end -1.1049 -0.724916)
			(stroke
				(width 0.1)
				(type default)
			)
			(layer "B.Fab")
		)
		(fp_line
			(start 1.1049 -0.724916)
			(end 1.1049 0.724916)
			(stroke
				(width 0.1)
				(type default)
			)
			(layer "B.Fab")
		)
		(fp_line
			(start 1.1049 0.724916)
			(end -1.1049 0.724916)
			(stroke
				(width 0.1)
				(type default)
			)
			(layer "B.Fab")
		)
		(pad "1" smd rect
			(at 0.889 0)
			(size 1.016 1.27)
			(layers "B.Cu" "B.Mask" "B.Paste")
			(net "PVCCINFAON_CPU1")
		)
		(pad "2" smd rect
			(at -0.889 0)
			(size 1.016 1.27)
			(layers "B.Cu" "B.Mask" "B.Paste")
			(net "GND")
		)
	)
	(footprint ""
		(layer "B.Cu")
		(at 176.955704 -112.97539)
		(property "Reference" "C1934"
			(at 0 0 0)
			(layer "B.SilkS")
			(hide yes)
			(effects
				(font
					(size 1.27 1.27)
				)
				(justify mirror)
			)
		)
		(property "Value" ""
			(at 0 0 0)
			(layer "B.Fab")
			(effects
				(font
					(size 1.27 1.27)
				)
				(justify mirror)
			)
		)
		(duplicate_pad_numbers_are_jumpers no)
		(fp_line
			(start -0.69215 -0.2921)
			(end -0.69215 0.2921)
			(stroke
				(width 0.1524)
				(type default)
			)
			(layer "B.SilkS")
		)
		(fp_line
			(start -0.69215 0.2921)
			(end 0.69215 0.2921)
			(stroke
				(width 0.1524)
				(type default)
			)
			(layer "B.SilkS")
		)
		(fp_line
			(start 0.69215 -0.2921)
			(end -0.69215 -0.2921)
			(stroke
				(width 0.1524)
				(type default)
			)
			(layer "B.SilkS")
		)
		(fp_line
			(start 0.69215 0.2921)
			(end 0.69215 -0.2921)
			(stroke
				(width 0.1524)
				(type default)
			)
			(layer "B.SilkS")
		)
		(fp_line
			(start -0.51435 -0.2794)
			(end -0.51435 0.2794)
			(stroke
				(width 0.1)
				(type default)
			)
			(layer "B.Fab")
		)
		(fp_line
			(start -0.51435 0.2794)
			(end 0.51435 0.2794)
			(stroke
				(width 0.1)
				(type default)
			)
			(layer "B.Fab")
		)
		(fp_line
			(start 0.51435 -0.2794)
			(end -0.51435 -0.2794)
			(stroke
				(width 0.1)
				(type default)
			)
			(layer "B.Fab")
		)
		(fp_line
			(start 0.51435 0.2794)
			(end 0.51435 -0.2794)
			(stroke
				(width 0.1)
				(type default)
			)
			(layer "B.Fab")
		)
		(pad "1" smd circle
			(at 0.40005 0 180)
			(size 0 0)
			(layers "B.Cu" "B.Mask" "B.Paste")
			(net "VCC_PLD_CORE")
		)
		(pad "2" smd circle
			(at -0.40005 0 180)
			(size 0 0)
			(layers "B.Cu" "B.Mask" "B.Paste")
			(net "GND")
		)
		(zone
			(layer "B.Cu")
			(hatch none 0.5)
			(connect_pads
				(clearance 0)
			)
			(min_thickness 0.25)
			(keepout
				(tracks not_allowed)
				(vias allowed)
				(pads allowed)
				(copperpour not_allowed)
				(footprints allowed)
			)
			(placement
				(enabled no)
				(sheetname "")
			)
			(fill
				(thermal_gap 0.5)
				(thermal_bridge_width 0.5)
				(island_removal_mode 0)
			)
			(polygon
				(pts
					(xy 177.146204 -112.88776) (xy 177.054764 -112.829594) (xy 176.855374 -112.829594) (xy 176.765204 -112.88776)
					(xy 176.765204 -113.06302) (xy 176.855374 -113.12144) (xy 177.054764 -113.12144) (xy 177.146204 -113.063274)
				)
			)
		)
	)
)
